# T6G (Grand Teton) — schematic netlist excerpt (pin names and nets, part order shuffled) for the footprints in the layout excerpt that follows; sources: Cadence DE-HDL packaged netlist, KiCad conversion of 04192023_DAF0TMB3IC0_F0TG_MB_C_brd_V02_OCP.brd

PU47  ISL99390FRZTR5935  ISL99390FRZ-TR5935 IC  pkg QFN21_6X5XB  page 195
  VOS  = PVDDCR_CPU0_P0_VOS4
  AGND  = GND
  VCC  = PVDDCR_CPU0_P0_VCC4
  PVCC  = PVDDCR_CPU0_P0_PVCC
  PGND1  = GND
  GL1  = NC_PVDDCR_CPU0_P0_GL1_4
  PGND2  = GND
  SW  = SW_PVDDCR_CPU0_P0_SW4
  VIN1  = SW_P12V_AUX_PVDDCR_CPU0_P0_FLT
  VIN2  = SW_P12V_AUX_PVDDCR_CPU0_P0_FLT
  DNC  = NC_PVDDCR_CPU0_P0_DNC4
  PHASE  = SW_PVDDCR_CPU0_P0_PH4
  BOOT  = SW_PVDDCR_CPU0_P0_BOOT4
  PWM  = PVDDCR_CPU0_P0_PWM4
  EN  = PVDDCR_CPU0_P0_VCC4
  TOUT_FLT  = PVDDCR_CPU0_P0_TEMP0
  LSET  = PVDDCR_CPU0_P0_LSET4
  IOUT  = PVDDCR_CPU0_P0_IMON4
  REFIN  = PVDDCR_CPU0_P0_VCCS
  PGND3  = GND
  GL2  = NC_PVDDCR_CPU0_P0_GL2_4

(kicad_pcb
	(version 20260206)
	(generator "pcbnew")
	(generator_version "10.0")
	(general
		(thickness 1.6)
		(legacy_teardrops no)
	)
	(paper "A4")
	(title_block
		(title "04192023_DAF0TMB3IC0_F0TG_MB_C_brd_V02_OCP.brd")
		(comment 1 "Grand Teton / footprints 1549-1549 of 8354")
	)
	(layers
		(0 "F.Cu" signal "TOP")
		(4 "In1.Cu" signal "GND")
		(6 "In2.Cu" signal "IN1")
		(8 "In3.Cu" signal "GND1")
		(10 "In4.Cu" signal "IN2")
		(12 "In5.Cu" signal "GND2")
		(14 "In6.Cu" signal "IN3")
		(16 "In7.Cu" signal "GND3")
		(18 "In8.Cu" signal "VCC")
		(20 "In9.Cu" signal "VCC1")
		(22 "In10.Cu" signal "GND4")
		(24 "In11.Cu" signal "IN4")
		(26 "In12.Cu" signal "GND5")
		(28 "In13.Cu" signal "IN5")
		(30 "In14.Cu" signal "GND6")
		(32 "In15.Cu" signal "IN6")
		(34 "In16.Cu" signal "GND7")
		(2 "B.Cu" signal "BOTTOM")
		(9 "F.Adhes" user "F.Adhesive")
		(11 "B.Adhes" user "B.Adhesive")
		(13 "F.Paste" user "Package Geometry/Pastemask Top")
		(15 "B.Paste" user "Package Geometry/Pastemask Bottom")
		(5 "F.SilkS" user "Ref Des/Silkscreen Top")
		(7 "B.SilkS" user "Ref Des/Silkscreen Bottom")
		(1 "F.Mask" user "Board Geometry/Soldermask Top")
		(3 "B.Mask" user "Board Geometry/Soldermask Bottom")
		(17 "Dwgs.User" user "User.Drawings")
		(19 "Cmts.User" user "User.Comments")
		(21 "Eco1.User" user "User.Eco1")
		(23 "Eco2.User" user "User.Eco2")
		(25 "Edge.Cuts" user "Board Geometry/Outline")
		(27 "Margin" user)
		(31 "F.CrtYd" user "Package Geometry/Place Bound Top")
		(29 "B.CrtYd" user "Package Geometry/Place Bound Bottom")
		(35 "F.Fab" user "Ref Des/Assembly Top")
		(33 "B.Fab" user "Ref Des/Assembly Bottom")
	)
	(footprint ""
		(layer "F.Cu")
		(at 389.409178 -182.743856 180)
		(property "Reference" "PU47"
			(at 4.140454 -6.180582 0)
			(unlocked yes)
			(layer "F.SilkS")
			(effects
				(font
					(size 0.7874 0.5842)
					(thickness 0.1524)
				)
				(justify left)
			)
		)
		(property "Value" ""
			(at 0 0 180)
			(layer "F.Fab")
			(effects
				(font
					(size 1.27 1.27)
				)
			)
		)
		(duplicate_pad_numbers_are_jumpers no)
		(fp_line
			(start 2.500122 2.999994)
			(end 2.2987 2.999994)
			(stroke
				(width 0.1524)
				(type default)
			)
			(layer "F.SilkS")
		)
		(fp_line
			(start 2.500122 2.339594)
			(end 2.500122 2.999994)
			(stroke
				(width 0.1524)
				(type default)
			)
			(layer "F.SilkS")
		)
		(fp_line
			(start 2.500122 -2.999994)
			(end 2.500122 -2.44348)
			(stroke
				(width 0.1524)
				(type default)
			)
			(layer "F.SilkS")
		)
		(fp_line
			(start 2.31394 -2.999994)
			(end 2.500122 -2.999994)
			(stroke
				(width 0.1524)
				(type default)
			)
			(layer "F.SilkS")
		)
		(fp_line
			(start -2.2987 2.999994)
			(end -2.500122 2.999994)
			(stroke
				(width 0.1524)
				(type default)
			)
			(layer "F.SilkS")
		)
		(fp_line
			(start -2.500122 2.999994)
			(end -2.500122 2.339594)
			(stroke
				(width 0.1524)
				(type default)
			)
			(layer "F.SilkS")
		)
		(fp_line
			(start -2.500122 0.6604)
			(end -2.500122 0.229108)
			(stroke
				(width 0.1524)
				(type default)
			)
			(layer "F.SilkS")
		)
		(fp_line
			(start -2.500122 -2.529078)
			(end -2.500122 -2.999994)
			(stroke
				(width 0.1524)
				(type default)
			)
			(layer "F.SilkS")
		)
		(fp_line
			(start -2.500122 -2.999994)
			(end -2.24409 -2.999994)
			(stroke
				(width 0.1524)
				(type default)
			)
			(layer "F.SilkS")
		)
		(fp_poly
			(pts
				(xy -2.700274 -2.537206) (xy -3.385312 -2.765806) (xy -2.928874 -3.222244)
			)
			(stroke
				(width 0)
				(type default)
			)
			(fill yes)
			(layer "F.SilkS")
		)
		(fp_line
			(start 2.500122 2.999994)
			(end -2.500122 2.999994)
			(stroke
				(width 0.1)
				(type default)
			)
			(layer "F.Fab")
		)
		(fp_line
			(start 2.500122 -2.999994)
			(end 2.500122 2.999994)
			(stroke
				(width 0.1)
				(type default)
			)
			(layer "F.Fab")
		)
		(fp_line
			(start -2.500122 2.999994)
			(end -2.500122 -2.999994)
			(stroke
				(width 0.1)
				(type default)
			)
			(layer "F.Fab")
		)
		(fp_line
			(start -2.500122 -2.999994)
			(end 2.500122 -2.999994)
			(stroke
				(width 0.1)
				(type default)
			)
			(layer "F.Fab")
		)
		(fp_poly
			(pts
				(xy -4.218432 -2.783078) (xy -4.218432 -1.767078) (xy -3.202432 -2.275078)
			)
			(stroke
				(width 0)
				(type default)
			)
			(fill yes)
			(layer "F.Fab")
		)
		(pad "1" smd rect
			(at -2.400046 -2.275078 270)
			(size 0.2286 0.6096)
			(layers "F.Cu" "F.Mask" "F.Paste")
			(net "PVDDCR_CPU0_P0_VOS4")
		)
		(pad "2" smd rect
			(at -2.400046 -1.82499 270)
			(size 0.2286 0.6096)
			(layers "F.Cu" "F.Mask" "F.Paste")
			(net "GND")
		)
		(pad "3" smd rect
			(at -2.400046 -1.374902 270)
			(size 0.2286 0.6096)
			(layers "F.Cu" "F.Mask" "F.Paste")
			(net "PVDDCR_CPU0_P0_VCC4")
		)
		(pad "4" smd rect
			(at -2.400046 -0.925068 270)
			(size 0.2286 0.6096)
			(layers "F.Cu" "F.Mask" "F.Paste")
			(net "PVDDCR_CPU0_P0_PVCC")
		)
		(pad "5" smd rect
			(at -2.400046 -0.47498 270)
			(size 0.2286 0.6096)
			(layers "F.Cu" "F.Mask" "F.Paste")
			(net "GND")
		)
		(pad "6" smd rect
			(at -2.400046 -0.024892 270)
			(size 0.2286 0.6096)
			(layers "F.Cu" "F.Mask" "F.Paste")
			(net "NC_PVDDCR_CPU0_P0_GL1_4")
		)
		(pad "7_9-20_24" smd circle
			(at 0 1.150112 270)
			(size 0 0)
			(layers "F.Cu" "F.Mask" "F.Paste")
			(net "GND")
		)
		(pad "10_19" smd rect
			(at 0 2.899918 270)
			(size 0.6096 4.318)
			(layers "F.Cu" "F.Mask" "F.Paste")
			(net "SW_PVDDCR_CPU0_P0_SW4")
		)
		(pad "25_29" smd rect
			(at 1.549908 -1.279906 90)
			(size 2.0574 2.3114)
			(layers "F.Cu" "F.Mask" "F.Paste")
			(net "SW_P12V_AUX_PVDDCR_CPU0_P0_FLT")
		)
		(pad "30" smd rect
			(at 2.05994 -2.899918 180)
			(size 0.2286 0.6096)
			(layers "F.Cu" "F.Mask" "F.Paste")
			(net "SW_P12V_AUX_PVDDCR_CPU0_P0_FLT")
		)
		(pad "31" smd rect
			(at 1.610106 -2.899918 180)
			(size 0.2286 0.6096)
			(layers "F.Cu" "F.Mask" "F.Paste")
			(net "NC_PVDDCR_CPU0_P0_DNC4")
		)
		(pad "32" smd rect
			(at 1.160018 -2.899918 180)
			(size 0.2286 0.6096)
			(layers "F.Cu" "F.Mask" "F.Paste")
			(net "SW_PVDDCR_CPU0_P0_PH4")
		)
		(pad "33" smd rect
			(at 0.70993 -2.899918 180)
			(size 0.2286 0.6096)
			(layers "F.Cu" "F.Mask" "F.Paste")
			(net "SW_PVDDCR_CPU0_P0_BOOT4")
		)
		(pad "34" smd rect
			(at 0.260096 -2.899918 180)
			(size 0.2286 0.6096)
			(layers "F.Cu" "F.Mask" "F.Paste")
			(net "PVDDCR_CPU0_P0_PWM4")
		)
		(pad "35" smd rect
			(at -0.189992 -2.899918 180)
			(size 0.2286 0.6096)
			(layers "F.Cu" "F.Mask" "F.Paste")
			(net "PVDDCR_CPU0_P0_VCC4")
		)
		(pad "36" smd rect
			(at -0.64008 -2.899918 180)
			(size 0.2286 0.6096)
			(layers "F.Cu" "F.Mask" "F.Paste")
			(net "PVDDCR_CPU0_P0_TEMP0")
		)
		(pad "37" smd rect
			(at -1.089914 -2.899918 180)
			(size 0.2286 0.6096)
			(layers "F.Cu" "F.Mask" "F.Paste")
			(net "PVDDCR_CPU0_P0_LSET4")
		)
		(pad "38" smd rect
			(at -1.540002 -2.899918 180)
			(size 0.2286 0.6096)
			(layers "F.Cu" "F.Mask" "F.Paste")
			(net "PVDDCR_CPU0_P0_IMON4")
		)
		(pad "39" smd rect
			(at -1.99009 -2.899918 180)
			(size 0.2286 0.6096)
			(layers "F.Cu" "F.Mask" "F.Paste")
			(net "PVDDCR_CPU0_P0_VCCS")
		)
		(pad "40" smd rect
			(at -0.87503 -1.27508 180)
			(size 1.7526 1.9558)
			(layers "F.Cu" "F.Mask" "F.Paste")
			(net "GND")
		)
		(pad "41" smd rect
			(at -1.525016 0.249936 90)
			(size 0.3048 0.4572)
			(layers "F.Cu" "F.Mask" "F.Paste")
			(net "NC_PVDDCR_CPU0_P0_GL2_4")
		)
		(zone
			(layer "F.Cu")
			(hatch none 0.5)
			(connect_pads
				(clearance 0)
			)
			(min_thickness 0.25)
			(keepout
				(tracks not_allowed)
				(vias allowed)
				(pads allowed)
				(copperpour not_allowed)
				(footprints allowed)
			)
			(placement
				(enabled no)
				(sheetname "")
			)
			(fill
				(thermal_gap 0.5)
				(thermal_bridge_width 0.5)
				(island_removal_mode 0)
			)
			(polygon
				(pts
					(xy 391.9093 -185.321702) (xy 391.9093 -184.99455) (xy 386.909056 -184.99455) (xy 386.909056 -185.322972)
					(xy 387.199378 -185.322972) (xy 387.199378 -185.288174) (xy 391.618978 -185.288174) (xy 391.618978 -185.321702)
				)
			)
		)
		(zone
			(layer "F.Cu")
			(hatch none 0.5)
			(connect_pads
				(clearance 0)
			)
			(min_thickness 0.25)
			(keepout
				(tracks not_allowed)
				(vias allowed)
				(pads allowed)
				(copperpour not_allowed)
				(footprints allowed)
			)
			(placement
				(enabled no)
				(sheetname "")
			)
			(fill
				(thermal_gap 0.5)
				(thermal_bridge_width 0.5)
				(island_removal_mode 0)
			)
			(polygon
				(pts
					(xy 389.357108 -182.497476) (xy 389.357108 -180.440076) (xy 391.211308 -180.440076) (xy 391.211308 -180.681122)
					(xy 391.453624 -180.681122) (xy 391.453624 -180.199538) (xy 387.624066 -180.199538) (xy 387.624066 -180.38445)
					(xy 389.06577 -180.38445) (xy 389.06577 -182.54345) (xy 386.909056 -182.54345) (xy 386.909056 -182.793132)
					(xy 389.061452 -182.793132)
				)
			)
		)
	)
)
